# T6G (Grand Teton) — schematic netlist excerpt (pin names and nets, part order shuffled) for the footprints in the layout excerpt that follows; sources: Cadence DE-HDL packaged netlist, KiCad conversion of 04192023_DAF0TMB3IC0_F0TG_MB_C_brd_V02_OCP.brd

R500  Q_RES  15 1% CHIP  pkg 0402LF  page 37 : A = M_A_CPU1_ALERT_N ; B = M_A_CPU1_ALERT_R_N
C2229  Q_CAP  22UF 4V 20% X6S  pkg C0402  page 69 : A = PVDDCR_CPU1_P0 ; B = GND

(kicad_pcb
	(version 20260206)
	(generator "pcbnew")
	(generator_version "10.0")
	(general
		(thickness 1.6)
		(legacy_teardrops no)
	)
	(paper "A4")
	(title_block
		(title "04192023_DAF0TMB3IC0_F0TG_MB_C_brd_V02_OCP.brd")
		(comment 1 "Grand Teton / footprints 7109-7110 of 8354")
	)
	(layers
		(0 "F.Cu" signal "TOP")
		(4 "In1.Cu" signal "GND")
		(6 "In2.Cu" signal "IN1")
		(8 "In3.Cu" signal "GND1")
		(10 "In4.Cu" signal "IN2")
		(12 "In5.Cu" signal "GND2")
		(14 "In6.Cu" signal "IN3")
		(16 "In7.Cu" signal "GND3")
		(18 "In8.Cu" signal "VCC")
		(20 "In9.Cu" signal "VCC1")
		(22 "In10.Cu" signal "GND4")
		(24 "In11.Cu" signal "IN4")
		(26 "In12.Cu" signal "GND5")
		(28 "In13.Cu" signal "IN5")
		(30 "In14.Cu" signal "GND6")
		(32 "In15.Cu" signal "IN6")
		(34 "In16.Cu" signal "GND7")
		(2 "B.Cu" signal "BOTTOM")
		(9 "F.Adhes" user "F.Adhesive")
		(11 "B.Adhes" user "B.Adhesive")
		(13 "F.Paste" user "Package Geometry/Pastemask Top")
		(15 "B.Paste" user "Package Geometry/Pastemask Bottom")
		(5 "F.SilkS" user "Ref Des/Silkscreen Top")
		(7 "B.SilkS" user "Ref Des/Silkscreen Bottom")
		(1 "F.Mask" user "Board Geometry/Soldermask Top")
		(3 "B.Mask" user "Board Geometry/Soldermask Bottom")
		(17 "Dwgs.User" user "User.Drawings")
		(19 "Cmts.User" user "User.Comments")
		(21 "Eco1.User" user "User.Eco1")
		(23 "Eco2.User" user "User.Eco2")
		(25 "Edge.Cuts" user "Board Geometry/Outline")
		(27 "Margin" user)
		(31 "F.CrtYd" user "Package Geometry/Place Bound Top")
		(29 "B.CrtYd" user "Package Geometry/Place Bound Bottom")
		(35 "F.Fab" user "Ref Des/Assembly Top")
		(33 "B.Fab" user "Ref Des/Assembly Bottom")
	)
	(footprint ""
		(layer "B.Cu")
		(at 354.025454 -268.41831)
		(property "Reference" "C2229"
			(at 0 0 0)
			(layer "B.SilkS")
			(hide yes)
			(effects
				(font
					(size 1.27 1.27)
				)
				(justify mirror)
			)
		)
		(property "Value" ""
			(at 0 0 0)
			(layer "B.Fab")
			(effects
				(font
					(size 1.27 1.27)
				)
				(justify mirror)
			)
		)
		(duplicate_pad_numbers_are_jumpers no)
		(fp_line
			(start -0.7874 -0.4064)
			(end -0.7874 0.4064)
			(stroke
				(width 0.1524)
				(type default)
			)
			(layer "B.SilkS")
		)
		(fp_line
			(start -0.7874 0.4064)
			(end 0.7874 0.4064)
			(stroke
				(width 0.1524)
				(type default)
			)
			(layer "B.SilkS")
		)
		(fp_line
			(start 0.7874 -0.4064)
			(end -0.7874 -0.4064)
			(stroke
				(width 0.1524)
				(type default)
			)
			(layer "B.SilkS")
		)
		(fp_line
			(start 0.7874 0.4064)
			(end 0.7874 -0.4064)
			(stroke
				(width 0.1524)
				(type default)
			)
			(layer "B.SilkS")
		)
		(fp_line
			(start -0.67945 -0.3048)
			(end -0.67945 0.3048)
			(stroke
				(width 0.1)
				(type default)
			)
			(layer "B.Fab")
		)
		(fp_line
			(start -0.67945 0.3048)
			(end -0.120396 0.3048)
			(stroke
				(width 0.1)
				(type default)
			)
			(layer "B.Fab")
		)
		(fp_line
			(start -0.12065 -0.3048)
			(end -0.67945 -0.3048)
			(stroke
				(width 0.1)
				(type default)
			)
			(layer "B.Fab")
		)
		(fp_line
			(start -0.12065 -0.2794)
			(end -0.12065 -0.3048)
			(stroke
				(width 0.1)
				(type default)
			)
			(layer "B.Fab")
		)
		(fp_line
			(start -0.120396 0.2794)
			(end 0.12065 0.2794)
			(stroke
				(width 0.1)
				(type default)
			)
			(layer "B.Fab")
		)
		(fp_line
			(start -0.120396 0.3048)
			(end -0.120396 0.2794)
			(stroke
				(width 0.1)
				(type default)
			)
			(layer "B.Fab")
		)
		(fp_line
			(start 0.12065 -0.305054)
			(end 0.12065 -0.2794)
			(stroke
				(width 0.1)
				(type default)
			)
			(layer "B.Fab")
		)
		(fp_line
			(start 0.12065 -0.2794)
			(end -0.12065 -0.2794)
			(stroke
				(width 0.1)
				(type default)
			)
			(layer "B.Fab")
		)
		(fp_line
			(start 0.12065 0.2794)
			(end 0.12065 0.3048)
			(stroke
				(width 0.1)
				(type default)
			)
			(layer "B.Fab")
		)
		(fp_line
			(start 0.12065 0.3048)
			(end 0.67945 0.3048)
			(stroke
				(width 0.1)
				(type default)
			)
			(layer "B.Fab")
		)
		(fp_line
			(start 0.67945 -0.305054)
			(end 0.12065 -0.305054)
			(stroke
				(width 0.1)
				(type default)
			)
			(layer "B.Fab")
		)
		(fp_line
			(start 0.67945 0.3048)
			(end 0.67945 -0.305054)
			(stroke
				(width 0.1)
				(type default)
			)
			(layer "B.Fab")
		)
		(pad "1" smd circle
			(at 0.40005 0 180)
			(size 0 0)
			(layers "B.Cu" "B.Mask" "B.Paste")
			(net "PVDDCR_CPU1_P0")
		)
		(pad "2" smd circle
			(at -0.40005 0 180)
			(size 0 0)
			(layers "B.Cu" "B.Mask" "B.Paste")
			(net "GND")
		)
	)
	(footprint ""
		(layer "B.Cu")
		(at 58.19521 -244.085364)
		(property "Reference" "R500"
			(at 0 0 0)
			(layer "B.SilkS")
			(hide yes)
			(effects
				(font
					(size 1.27 1.27)
				)
				(justify mirror)
			)
		)
		(property "Value" ""
			(at 0 0 0)
			(layer "B.Fab")
			(effects
				(font
					(size 1.27 1.27)
				)
				(justify mirror)
			)
		)
		(duplicate_pad_numbers_are_jumpers no)
		(fp_line
			(start -0.7874 -0.4064)
			(end -0.7874 0.4064)
			(stroke
				(width 0.1524)
				(type default)
			)
			(layer "B.SilkS")
		)
		(fp_line
			(start -0.7874 0.4064)
			(end 0.7874 0.4064)
			(stroke
				(width 0.1524)
				(type default)
			)
			(layer "B.SilkS")
		)
		(fp_line
			(start 0.7874 -0.4064)
			(end -0.7874 -0.4064)
			(stroke
				(width 0.1524)
				(type default)
			)
			(layer "B.SilkS")
		)
		(fp_line
			(start 0.7874 0.4064)
			(end 0.7874 -0.4064)
			(stroke
				(width 0.1524)
				(type default)
			)
			(layer "B.SilkS")
		)
		(fp_line
			(start -0.67945 -0.3048)
			(end -0.67945 0.3048)
			(stroke
				(width 0.1)
				(type default)
			)
			(layer "B.Fab")
		)
		(fp_line
			(start -0.67945 0.3048)
			(end -0.120396 0.3048)
			(stroke
				(width 0.1)
				(type default)
			)
			(layer "B.Fab")
		)
		(fp_line
			(start -0.12065 -0.3048)
			(end -0.67945 -0.3048)
			(stroke
				(width 0.1)
				(type default)
			)
			(layer "B.Fab")
		)
		(fp_line
			(start -0.12065 -0.2794)
			(end -0.12065 -0.3048)
			(stroke
				(width 0.1)
				(type default)
			)
			(layer "B.Fab")
		)
		(fp_line
			(start -0.120396 0.2794)
			(end 0.12065 0.2794)
			(stroke
				(width 0.1)
				(type default)
			)
			(layer "B.Fab")
		)
		(fp_line
			(start -0.120396 0.3048)
			(end -0.120396 0.2794)
			(stroke
				(width 0.1)
				(type default)
			)
			(layer "B.Fab")
		)
		(fp_line
			(start 0.12065 -0.305054)
			(end 0.12065 -0.2794)
			(stroke
				(width 0.1)
				(type default)
			)
			(layer "B.Fab")
		)
		(fp_line
			(start 0.12065 -0.2794)
			(end -0.12065 -0.2794)
			(stroke
				(width 0.1)
				(type default)
			)
			(layer "B.Fab")
		)
		(fp_line
			(start 0.12065 0.2794)
			(end 0.12065 0.3048)
			(stroke
				(width 0.1)
				(type default)
			)
			(layer "B.Fab")
		)
		(fp_line
			(start 0.12065 0.3048)
			(end 0.67945 0.3048)
			(stroke
				(width 0.1)
				(type default)
			)
			(layer "B.Fab")
		)
		(fp_line
			(start 0.67945 -0.305054)
			(end 0.12065 -0.305054)
			(stroke
				(width 0.1)
				(type default)
			)
			(layer "B.Fab")
		)
		(fp_line
			(start 0.67945 0.3048)
			(end 0.67945 -0.305054)
			(stroke
				(width 0.1)
				(type default)
			)
			(layer "B.Fab")
		)
		(pad "1" smd circle
			(at 0.40005 0 180)
			(size 0 0)
			(layers "B.Cu" "B.Mask" "B.Paste")
			(net "M_A_CPU1_ALERT_N")
		)
		(pad "2" smd circle
			(at -0.40005 0 180)
			(size 0 0)
			(layers "B.Cu" "B.Mask" "B.Paste")
			(net "M_A_CPU1_ALERT_R_N")
		)
	)
)
